(kicad_pcb
	(version 20260206)
	(generator "pcbnew")
	(generator_version "10.0")
	(general
		(thickness 1.6)
		(legacy_teardrops no)
	)
	(paper "A4")
	(title_block
		(title "Wiwynn_Tioga_Pass_MB.brd")
		(comment 1 "Tioga Pass / footprints 4313-4320 of 4770")
	)
	(layers
		(0 "F.Cu" signal "TOP")
		(4 "In1.Cu" signal "L2GND")
		(6 "In2.Cu" signal "L3")
		(8 "In3.Cu" signal "L4GND")
		(10 "In4.Cu" signal "L5")
		(12 "In5.Cu" signal "L6GND")
		(14 "In6.Cu" signal "L7VCC")
		(16 "In7.Cu" signal "L8VCC")
		(18 "In8.Cu" signal "L9GND")
		(20 "In9.Cu" signal "L10")
		(22 "In10.Cu" signal "L11GND")
		(24 "In11.Cu" signal "L12")
		(26 "In12.Cu" signal "L13GND")
		(2 "B.Cu" signal "BOTTOM")
		(9 "F.Adhes" user "F.Adhesive")
		(11 "B.Adhes" user "B.Adhesive")
		(13 "F.Paste" user "Package Geometry/Pastemask Top")
		(15 "B.Paste" user "Package Geometry/Pastemask Bottom")
		(5 "F.SilkS" user "Ref Des/Silkscreen Top")
		(7 "B.SilkS" user "Ref Des/Silkscreen Bottom")
		(1 "F.Mask" user "Board Geometry/Soldermask Top")
		(3 "B.Mask" user "Board Geometry/Soldermask Bottom")
		(17 "Dwgs.User" user "User.Drawings")
		(19 "Cmts.User" user "User.Comments")
		(21 "Eco1.User" user "User.Eco1")
		(23 "Eco2.User" user "User.Eco2")
		(25 "Edge.Cuts" user "Board Geometry/Outline")
		(27 "Margin" user)
		(31 "F.CrtYd" user "Package Geometry/Place Bound Top")
		(29 "B.CrtYd" user "Package Geometry/Place Bound Bottom")
		(35 "F.Fab" user "Ref Des/Assembly Top")
		(33 "B.Fab" user "Ref Des/Assembly Bottom")
	)
	(footprint ""
		(layer "B.Cu")
		(at 370.967 -152.019 90)
		(property "Reference" "C22W24"
			(at 0 0 90)
			(layer "B.SilkS")
			(hide yes)
			(effects
				(font
					(size 1.27 1.27)
				)
				(justify mirror)
			)
		)
		(property "Value" "*"
			(at 0.0762 -6.2357 90)
			(unlocked yes)
			(layer "B.Fab")
			(hide yes)
			(effects
				(font
					(size 1.27 1.016)
					(thickness 0.1524)
				)
				(justify mirror)
			)
		)
		(property "Device Type" "SC22U16V5MX-4-GP_SMD-BCG5-SC22A"
			(at 0.0762 -8.2677 90)
			(unlocked yes)
			(layer "B.Fab")
			(hide yes)
			(effects
				(font
					(size 1.27 1.016)
					(thickness 0.1524)
				)
				(justify mirror)
			)
		)
		(duplicate_pad_numbers_are_jumpers no)
		(fp_line
			(start -0.635 0)
			(end 0.635 0)
			(stroke
				(width 0.508)
				(type default)
			)
			(layer "B.SilkS")
		)
		(fp_rect
			(start 0.9652 1.778)
			(end -0.9652 -1.778)
			(stroke
				(width 0)
				(type default)
			)
			(fill no)
			(layer "B.CrtYd")
		)
		(fp_poly
			(pts
				(xy 0.9652 -1.778) (xy -0.9652 -1.778) (xy -0.9652 1.778) (xy 0.9652 1.778)
			)
			(stroke
				(width 0)
				(type default)
			)
			(fill no)
			(layer "B.Fab")
		)
		(pad "1" smd rect
			(at 0 -0.9652 270)
			(size 1.397 1.143)
			(layers "B.Cu" "B.Mask" "B.Paste")
			(net "VR_FET_SW_P12V_STBY_PVDDQ_DEF")
		)
		(pad "2" smd rect
			(at 0 0.9652 270)
			(size 1.397 1.143)
			(layers "B.Cu" "B.Mask" "B.Paste")
			(net "GND")
		)
	)
	(footprint ""
		(layer "B.Cu")
		(at 391.18794 -139.66698 180)
		(property "Reference" "C2L25"
			(at -3.10007 3.24612 270)
			(unlocked yes)
			(layer "B.SilkS")
			(effects
				(font
					(size 0.7874 0.5842)
					(thickness 0.1524)
				)
				(justify mirror)
			)
		)
		(property "Value" ""
			(at 0 0 0)
			(layer "B.Fab")
			(effects
				(font
					(size 1.27 1.27)
				)
				(justify mirror)
			)
		)
		(duplicate_pad_numbers_are_jumpers no)
		(fp_line
			(start 2.563114 1.633728)
			(end 1.6002 1.633728)
			(stroke
				(width 0.1524)
				(type default)
			)
			(layer "B.SilkS")
		)
		(fp_line
			(start 2.563114 -1.616456)
			(end 2.563114 1.633728)
			(stroke
				(width 0.1524)
				(type default)
			)
			(layer "B.SilkS")
		)
		(fp_line
			(start 2.286 7.366)
			(end 2.286 1.632712)
			(stroke
				(width 0.1524)
				(type default)
			)
			(layer "B.SilkS")
		)
		(fp_line
			(start 2.286 7.366)
			(end 1.60147 7.366)
			(stroke
				(width 0.1524)
				(type default)
			)
			(layer "B.SilkS")
		)
		(fp_line
			(start 1.6002 -1.616456)
			(end 2.563114 -1.616456)
			(stroke
				(width 0.1524)
				(type default)
			)
			(layer "B.SilkS")
		)
		(fp_line
			(start -1.6002 -1.616456)
			(end -2.504948 -1.616456)
			(stroke
				(width 0.1524)
				(type default)
			)
			(layer "B.SilkS")
		)
		(fp_line
			(start -2.286 7.366)
			(end -1.600708 7.366)
			(stroke
				(width 0.1524)
				(type default)
			)
			(layer "B.SilkS")
		)
		(fp_line
			(start -2.286 7.366)
			(end -2.286 1.63195)
			(stroke
				(width 0.1524)
				(type default)
			)
			(layer "B.SilkS")
		)
		(fp_line
			(start -2.504948 1.633728)
			(end -1.6002 1.633728)
			(stroke
				(width 0.1524)
				(type default)
			)
			(layer "B.SilkS")
		)
		(fp_line
			(start -2.504948 -1.616456)
			(end -2.504948 1.633728)
			(stroke
				(width 0.1524)
				(type default)
			)
			(layer "B.SilkS")
		)
		(fp_rect
			(start 2.286 7.366)
			(end -2.286 -0.254)
			(stroke
				(width 0)
				(type default)
			)
			(fill no)
			(layer "B.CrtYd")
		)
		(fp_line
			(start 2.286 7.366)
			(end 2.286 -0.254)
			(stroke
				(width 0.1)
				(type default)
			)
			(layer "B.Fab")
		)
		(fp_line
			(start 2.286 -0.254)
			(end -2.286 -0.254)
			(stroke
				(width 0.1)
				(type default)
			)
			(layer "B.Fab")
		)
		(fp_line
			(start -2.286 7.366)
			(end 2.286 7.366)
			(stroke
				(width 0.1)
				(type default)
			)
			(layer "B.Fab")
		)
		(fp_line
			(start -2.286 -0.254)
			(end -2.286 7.366)
			(stroke
				(width 0.1)
				(type default)
			)
			(layer "B.Fab")
		)
		(pad "1" smd rect
			(at 0 0)
			(size 2.54 3.048)
			(layers "B.Cu" "B.Mask" "B.Paste")
			(net "P1V05_PCH_STBY")
		)
		(pad "2" smd rect
			(at 0 7.112)
			(size 2.54 3.048)
			(layers "B.Cu" "B.Mask" "B.Paste")
			(net "GND")
		)
	)
	(footprint ""
		(layer "B.Cu")
		(at 162.463988 -71.982076 180)
		(property "Reference" "R7P30"
			(at 0 0 0)
			(layer "B.SilkS")
			(hide yes)
			(effects
				(font
					(size 1.27 1.27)
				)
				(justify mirror)
			)
		)
		(property "Value" ""
			(at 0 0 0)
			(layer "B.Fab")
			(effects
				(font
					(size 1.27 1.27)
				)
				(justify mirror)
			)
		)
		(duplicate_pad_numbers_are_jumpers no)
		(fp_poly
			(pts
				(xy 0.2794 -0.1016) (xy -0.2794 -0.1016) (xy -0.2794 0.9906) (xy 0.2794 0.9906)
			)
			(stroke
				(width 0)
				(type default)
			)
			(fill no)
			(layer "B.CrtYd")
		)
		(fp_line
			(start 0.2794 0.9906)
			(end -0.2794 0.9906)
			(stroke
				(width 0.1)
				(type default)
			)
			(layer "B.Fab")
		)
		(fp_line
			(start 0.2794 -0.1016)
			(end 0.2794 0.9906)
			(stroke
				(width 0.1)
				(type default)
			)
			(layer "B.Fab")
		)
		(fp_line
			(start -0.2794 0.9906)
			(end -0.2794 -0.1016)
			(stroke
				(width 0.1)
				(type default)
			)
			(layer "B.Fab")
		)
		(fp_line
			(start -0.2794 -0.1016)
			(end 0.2794 -0.1016)
			(stroke
				(width 0.1)
				(type default)
			)
			(layer "B.Fab")
		)
		(pad "1" smd rect
			(at 0 0)
			(size 0.508 0.508)
			(layers "B.Cu" "B.Mask" "B.Paste")
			(net "PVCCIO_CPU0")
		)
		(pad "2" smd rect
			(at 0 0.889)
			(size 0.508 0.508)
			(layers "B.Cu" "B.Mask" "B.Paste")
			(net "XDP_CPU_MBP0_N")
		)
		(zone
			(layer "B.Cu")
			(hatch none 0.5)
			(connect_pads
				(clearance 0)
			)
			(min_thickness 0.25)
			(keepout
				(tracks not_allowed)
				(vias allowed)
				(pads allowed)
				(copperpour not_allowed)
				(footprints allowed)
			)
			(placement
				(enabled no)
				(sheetname "")
			)
			(fill
				(thermal_gap 0.5)
				(thermal_bridge_width 0.5)
				(island_removal_mode 0)
			)
			(polygon
				(pts
					(xy 162.209988 -72.617076) (xy 162.717988 -72.617076) (xy 162.717988 -72.236076) (xy 162.209988 -72.236076)
				)
			)
		)
		(zone
			(layer "B.Cu")
			(hatch none 0.5)
			(connect_pads
				(clearance 0)
			)
			(min_thickness 0.25)
			(keepout
				(tracks allowed)
				(vias not_allowed)
				(pads allowed)
				(copperpour not_allowed)
				(footprints allowed)
			)
			(placement
				(enabled no)
				(sheetname "")
			)
			(fill
				(thermal_gap 0.5)
				(thermal_bridge_width 0.5)
				(island_removal_mode 0)
			)
			(polygon
				(pts
					(xy 162.209988 -72.236076) (xy 162.717988 -72.236076) (xy 162.717988 -72.617076) (xy 162.209988 -72.617076)
				)
			)
		)
	)
	(footprint ""
		(layer "B.Cu")
		(at 481.623116 -144.009872 90)
		(property "Reference" "R6W8"
			(at 0.8382 -0.67818 90)
			(unlocked yes)
			(layer "B.SilkS")
			(effects
				(font
					(size 0.4064 0.254)
					(thickness 0.1524)
				)
				(justify left mirror)
			)
		)
		(property "Value" ""
			(at 0 0 90)
			(layer "B.Fab")
			(effects
				(font
					(size 1.27 1.27)
				)
				(justify mirror)
			)
		)
		(duplicate_pad_numbers_are_jumpers no)
		(fp_poly
			(pts
				(xy 0.2794 -0.1016) (xy -0.2794 -0.1016) (xy -0.2794 0.9906) (xy 0.2794 0.9906)
			)
			(stroke
				(width 0)
				(type default)
			)
			(fill no)
			(layer "B.CrtYd")
		)
		(fp_line
			(start 0.2794 -0.1016)
			(end 0.2794 0.9906)
			(stroke
				(width 0.1)
				(type default)
			)
			(layer "B.Fab")
		)
		(fp_line
			(start -0.2794 -0.1016)
			(end 0.2794 -0.1016)
			(stroke
				(width 0.1)
				(type default)
			)
			(layer "B.Fab")
		)
		(fp_line
			(start 0.2794 0.9906)
			(end -0.2794 0.9906)
			(stroke
				(width 0.1)
				(type default)
			)
			(layer "B.Fab")
		)
		(fp_line
			(start -0.2794 0.9906)
			(end -0.2794 -0.1016)
			(stroke
				(width 0.1)
				(type default)
			)
			(layer "B.Fab")
		)
		(pad "1" smd rect
			(at 0 0 270)
			(size 0.508 0.508)
			(layers "B.Cu" "B.Mask" "B.Paste")
			(net "PCA9555_A1")
		)
		(pad "2" smd rect
			(at 0 0.889 270)
			(size 0.508 0.508)
			(layers "B.Cu" "B.Mask" "B.Paste")
			(net "GND")
		)
		(zone
			(layer "B.Cu")
			(hatch none 0.5)
			(connect_pads
				(clearance 0)
			)
			(min_thickness 0.25)
			(keepout
				(tracks allowed)
				(vias not_allowed)
				(pads allowed)
				(copperpour not_allowed)
				(footprints allowed)
			)
			(placement
				(enabled no)
				(sheetname "")
			)
			(fill
				(thermal_gap 0.5)
				(thermal_bridge_width 0.5)
				(island_removal_mode 0)
			)
			(polygon
				(pts
					(xy 481.877116 -144.263872) (xy 481.877116 -143.755872) (xy 482.258116 -143.755872) (xy 482.258116 -144.263872)
				)
			)
		)
		(zone
			(layer "B.Cu")
			(hatch none 0.5)
			(connect_pads
				(clearance 0)
			)
			(min_thickness 0.25)
			(keepout
				(tracks not_allowed)
				(vias allowed)
				(pads allowed)
				(copperpour not_allowed)
				(footprints allowed)
			)
			(placement
				(enabled no)
				(sheetname "")
			)
			(fill
				(thermal_gap 0.5)
				(thermal_bridge_width 0.5)
				(island_removal_mode 0)
			)
			(polygon
				(pts
					(xy 482.258116 -144.263872) (xy 482.258116 -143.755872) (xy 481.877116 -143.755872) (xy 481.877116 -144.263872)
				)
			)
		)
	)
	(footprint ""
		(layer "B.Cu")
		(at 407.416 -103.8225)
		(property "Reference" "C2N23"
			(at 0 0 0)
			(layer "B.SilkS")
			(hide yes)
			(effects
				(font
					(size 1.27 1.27)
				)
				(justify mirror)
			)
		)
		(property "Value" ""
			(at 0 0 0)
			(layer "B.Fab")
			(effects
				(font
					(size 1.27 1.27)
				)
				(justify mirror)
			)
		)
		(duplicate_pad_numbers_are_jumpers no)
		(fp_poly
			(pts
				(xy 0.4953 -0.2032) (xy -0.4953 -0.2032) (xy -0.4953 1.6002) (xy 0.4953 1.6002)
			)
			(stroke
				(width 0)
				(type default)
			)
			(fill no)
			(layer "B.CrtYd")
		)
		(fp_line
			(start -0.4953 -0.2032)
			(end -0.4953 1.6002)
			(stroke
				(width 0.1)
				(type default)
			)
			(layer "B.Fab")
		)
		(fp_line
			(start -0.4953 1.6002)
			(end 0.4953 1.6002)
			(stroke
				(width 0.1)
				(type default)
			)
			(layer "B.Fab")
		)
		(fp_line
			(start 0.4953 -0.2032)
			(end -0.4953 -0.2032)
			(stroke
				(width 0.1)
				(type default)
			)
			(layer "B.Fab")
		)
		(fp_line
			(start 0.4953 1.6002)
			(end 0.4953 -0.2032)
			(stroke
				(width 0.1)
				(type default)
			)
			(layer "B.Fab")
		)
		(pad "1" smd rect
			(at 0 0 180)
			(size 0.762 0.889)
			(layers "B.Cu" "B.Mask" "B.Paste")
			(net "P3V3_STBY")
		)
		(pad "2" smd rect
			(at 0 1.397 180)
			(size 0.762 0.889)
			(layers "B.Cu" "B.Mask" "B.Paste")
			(net "GND")
		)
		(zone
			(layer "B.Cu")
			(hatch none 0.5)
			(connect_pads
				(clearance 0)
			)
			(min_thickness 0.25)
			(keepout
				(tracks not_allowed)
				(vias allowed)
				(pads allowed)
				(copperpour not_allowed)
				(footprints allowed)
			)
			(placement
				(enabled no)
				(sheetname "")
			)
			(fill
				(thermal_gap 0.5)
				(thermal_bridge_width 0.5)
				(island_removal_mode 0)
			)
			(polygon
				(pts
					(xy 407.797 -103.378) (xy 407.035 -103.378) (xy 407.035 -102.87) (xy 407.797 -102.87)
				)
			)
		)
	)
	(footprint ""
		(layer "B.Cu")
		(at 172.847 -126.111)
		(property "Reference" "R6M4"
			(at 0 0 0)
			(layer "B.SilkS")
			(hide yes)
			(effects
				(font
					(size 1.27 1.27)
				)
				(justify mirror)
			)
		)
		(property "Value" ""
			(at 0 0 0)
			(layer "B.Fab")
			(effects
				(font
					(size 1.27 1.27)
				)
				(justify mirror)
			)
		)
		(duplicate_pad_numbers_are_jumpers no)
		(fp_poly
			(pts
				(xy 0.2794 -0.1016) (xy -0.2794 -0.1016) (xy -0.2794 0.9906) (xy 0.2794 0.9906)
			)
			(stroke
				(width 0)
				(type default)
			)
			(fill no)
			(layer "B.CrtYd")
		)
		(fp_line
			(start -0.2794 -0.1016)
			(end 0.2794 -0.1016)
			(stroke
				(width 0.1)
				(type default)
			)
			(layer "B.Fab")
		)
		(fp_line
			(start -0.2794 0.9906)
			(end -0.2794 -0.1016)
			(stroke
				(width 0.1)
				(type default)
			)
			(layer "B.Fab")
		)
		(fp_line
			(start 0.2794 -0.1016)
			(end 0.2794 0.9906)
			(stroke
				(width 0.1)
				(type default)
			)
			(layer "B.Fab")
		)
		(fp_line
			(start 0.2794 0.9906)
			(end -0.2794 0.9906)
			(stroke
				(width 0.1)
				(type default)
			)
			(layer "B.Fab")
		)
		(pad "1" smd rect
			(at 0 0 180)
			(size 0.508 0.508)
			(layers "B.Cu" "B.Mask" "B.Paste")
			(net "P3V3")
		)
		(pad "2" smd rect
			(at 0 0.889 180)
			(size 0.508 0.508)
			(layers "B.Cu" "B.Mask" "B.Paste")
			(net "H_CPU1_MEMKLM_MEMHOT")
		)
		(zone
			(layer "B.Cu")
			(hatch none 0.5)
			(connect_pads
				(clearance 0)
			)
			(min_thickness 0.25)
			(keepout
				(tracks allowed)
				(vias not_allowed)
				(pads allowed)
				(copperpour not_allowed)
				(footprints allowed)
			)
			(placement
				(enabled no)
				(sheetname "")
			)
			(fill
				(thermal_gap 0.5)
				(thermal_bridge_width 0.5)
				(island_removal_mode 0)
			)
			(polygon
				(pts
					(xy 173.101 -125.857) (xy 172.593 -125.857) (xy 172.593 -125.476) (xy 173.101 -125.476)
				)
			)
		)
		(zone
			(layer "B.Cu")
			(hatch none 0.5)
			(connect_pads
				(clearance 0)
			)
			(min_thickness 0.25)
			(keepout
				(tracks not_allowed)
				(vias allowed)
				(pads allowed)
				(copperpour not_allowed)
				(footprints allowed)
			)
			(placement
				(enabled no)
				(sheetname "")
			)
			(fill
				(thermal_gap 0.5)
				(thermal_bridge_width 0.5)
				(island_removal_mode 0)
			)
			(polygon
				(pts
					(xy 173.101 -125.476) (xy 172.593 -125.476) (xy 172.593 -125.857) (xy 173.101 -125.857)
				)
			)
		)
	)
	(footprint ""
		(layer "B.Cu")
		(at -3.0226 -9.017 -90)
		(property "Reference" "C22W1"
			(at 0 0 90)
			(layer "B.SilkS")
			(hide yes)
			(effects
				(font
					(size 1.27 1.27)
				)
				(justify mirror)
			)
		)
		(property "Value" "*"
			(at 0.0762 -6.2357 270)
			(unlocked yes)
			(layer "B.Fab")
			(hide yes)
			(effects
				(font
					(size 1.27 1.016)
					(thickness 0.1524)
				)
				(justify mirror)
			)
		)
		(property "Device Type" "SC22U16V5MX-4-GP_SMD-BCG5-SC22A"
			(at 0.0762 -8.2677 270)
			(unlocked yes)
			(layer "B.Fab")
			(hide yes)
			(effects
				(font
					(size 1.27 1.016)
					(thickness 0.1524)
				)
				(justify mirror)
			)
		)
		(duplicate_pad_numbers_are_jumpers no)
		(fp_line
			(start -0.635 0)
			(end 0.635 0)
			(stroke
				(width 0.508)
				(type default)
			)
			(layer "B.SilkS")
		)
		(fp_rect
			(start 0.9652 1.778)
			(end -0.9652 -1.778)
			(stroke
				(width 0)
				(type default)
			)
			(fill no)
			(layer "B.CrtYd")
		)
		(fp_poly
			(pts
				(xy 0.9652 -1.778) (xy -0.9652 -1.778) (xy -0.9652 1.778) (xy 0.9652 1.778)
			)
			(stroke
				(width 0)
				(type default)
			)
			(fill no)
			(layer "B.Fab")
		)
		(pad "1" smd rect
			(at 0 -0.9652 90)
			(size 1.397 1.143)
			(layers "B.Cu" "B.Mask" "B.Paste")
			(net "VR_FET_SW_P12V_STBY_PVDDQ_GHJ")
		)
		(pad "2" smd rect
			(at 0 0.9652 90)
			(size 1.397 1.143)
			(layers "B.Cu" "B.Mask" "B.Paste")
			(net "GND")
		)
	)
	(footprint ""
		(layer "B.Cu")
		(at 191.897 -154.559 180)
		(property "Reference" "C6L2"
			(at 0 0 0)
			(layer "B.SilkS")
			(hide yes)
			(effects
				(font
					(size 1.27 1.27)
				)
				(justify mirror)
			)
		)
		(property "Value" ""
			(at 0 0 0)
			(layer "B.Fab")
			(effects
				(font
					(size 1.27 1.27)
				)
				(justify mirror)
			)
		)
		(duplicate_pad_numbers_are_jumpers no)
		(fp_poly
			(pts
				(xy -0.3048 -0.1016) (xy -0.3048 0.9906) (xy 0.3048 0.9906) (xy 0.3048 -0.1016)
			)
			(stroke
				(width 0)
				(type default)
			)
			(fill no)
			(layer "B.CrtYd")
		)
		(fp_line
			(start 0.3048 0.9906)
			(end -0.3048 0.9906)
			(stroke
				(width 0.1)
				(type default)
			)
			(layer "B.Fab")
		)
		(fp_line
			(start 0.3048 -0.1016)
			(end 0.3048 0.9906)
			(stroke
				(width 0.1)
				(type default)
			)
			(layer "B.Fab")
		)
		(fp_line
			(start -0.3048 0.9906)
			(end -0.3048 -0.1016)
			(stroke
				(width 0.1)
				(type default)
			)
			(layer "B.Fab")
		)
		(fp_line
			(start -0.3048 -0.1016)
			(end 0.3048 -0.1016)
			(stroke
				(width 0.1)
				(type default)
			)
			(layer "B.Fab")
		)
		(pad "1" smd rect
			(at 0 0)
			(size 0.508 0.508)
			(layers "B.Cu" "B.Mask" "B.Paste")
			(net "M_F_CPU_VREF")
		)
		(pad "2" smd rect
			(at 0 0.889)
			(size 0.508 0.508)
			(layers "B.Cu" "B.Mask" "B.Paste")
			(net "GND")
		)
		(zone
			(layer "B.Cu")
			(hatch none 0.5)
			(connect_pads
				(clearance 0)
			)
			(min_thickness 0.25)
			(keepout
				(tracks not_allowed)
				(vias allowed)
				(pads allowed)
				(copperpour not_allowed)
				(footprints allowed)
			)
			(placement
				(enabled no)
				(sheetname "")
			)
			(fill
				(thermal_gap 0.5)
				(thermal_bridge_width 0.5)
				(island_removal_mode 0)
			)
			(polygon
				(pts
					(xy 191.643 -155.194) (xy 192.151 -155.194) (xy 192.151 -154.813) (xy 191.643 -154.813)
				)
			)
		)
		(zone
			(layer "B.Cu")
			(hatch none 0.5)
			(connect_pads
				(clearance 0)
			)
			(min_thickness 0.25)
			(keepout
				(tracks allowed)
				(vias not_allowed)
				(pads allowed)
				(copperpour not_allowed)
				(footprints allowed)
			)
			(placement
				(enabled no)
				(sheetname "")
			)
			(fill
				(thermal_gap 0.5)
				(thermal_bridge_width 0.5)
				(island_removal_mode 0)
			)
			(polygon
				(pts
					(xy 191.643 -154.813) (xy 192.151 -154.813) (xy 192.151 -155.194) (xy 191.643 -155.194)
				)
			)
		)
	)
)
